(kicad_pcb
	(version 20260206)
	(generator "pcbnew")
	(generator_version "10.0")
	(general
		(thickness 1.6)
		(legacy_teardrops no)
	)
	(paper "A4")
	(title_block
		(title "baseboard — 13948-1b.1110WZS1818.brd")
		(comment 1 "Honey Badger (Wiwynn) / footprints 1275-1283 of 2523")
	)
	(layers
		(0 "F.Cu" signal "TOP")
		(4 "In1.Cu" signal "L2GND")
		(6 "In2.Cu" signal "L3")
		(8 "In3.Cu" signal "L4VCC")
		(10 "In4.Cu" signal "L5VCC")
		(12 "In5.Cu" signal "L6")
		(14 "In6.Cu" signal "L7GND")
		(2 "B.Cu" signal "BOTTOM")
		(9 "F.Adhes" user "F.Adhesive")
		(11 "B.Adhes" user "B.Adhesive")
		(13 "F.Paste" user "Package Geometry/Pastemask Top")
		(15 "B.Paste" user "Package Geometry/Pastemask Bottom")
		(5 "F.SilkS" user "Ref Des/Silkscreen Top")
		(7 "B.SilkS" user "Ref Des/Silkscreen Bottom")
		(1 "F.Mask" user "Board Geometry/Soldermask Top")
		(3 "B.Mask" user "Board Geometry/Soldermask Bottom")
		(17 "Dwgs.User" user "User.Drawings")
		(19 "Cmts.User" user "User.Comments")
		(21 "Eco1.User" user "User.Eco1")
		(23 "Eco2.User" user "User.Eco2")
		(25 "Edge.Cuts" user "Board Geometry/Outline")
		(27 "Margin" user)
		(31 "F.CrtYd" user "Package Geometry/Place Bound Top")
		(29 "B.CrtYd" user "Package Geometry/Place Bound Bottom")
		(35 "F.Fab" user "Ref Des/Assembly Top")
		(33 "B.Fab" user "Ref Des/Assembly Bottom")
	)
	(footprint ""
		(layer "F.Cu")
		(at 81.285842 -120.721882 -90)
		(property "Reference" "SR741"
			(at 0 0 270)
			(layer "F.SilkS")
			(hide yes)
			(effects
				(font
					(size 1.27 1.27)
				)
			)
		)
		(property "Value" "2K2R2F-GP"
			(at 0.064008 -3.993896 270)
			(unlocked yes)
			(layer "F.Fab")
			(hide yes)
			(effects
				(font
					(size 1.016 1.016)
					(thickness 0.1524)
				)
			)
		)
		(property "Device Type" "R402H16"
			(at 0.064008 -5.517896 270)
			(unlocked yes)
			(layer "F.Fab")
			(hide yes)
			(effects
				(font
					(size 1.016 1.016)
					(thickness 0.1524)
				)
			)
		)
		(duplicate_pad_numbers_are_jumpers no)
		(fp_line
			(start -0.508 -0.9398)
			(end -0.508 0.9398)
			(stroke
				(width 0.1524)
				(type default)
			)
			(layer "F.SilkS")
		)
		(fp_line
			(start 0.508 -0.9398)
			(end -0.508 -0.9398)
			(stroke
				(width 0.1524)
				(type default)
			)
			(layer "F.SilkS")
		)
		(fp_rect
			(start -0.508 0.9398)
			(end 0.508 -0.9398)
			(stroke
				(width 0)
				(type default)
			)
			(fill no)
			(layer "F.CrtYd")
		)
		(fp_rect
			(start -0.508 0.9398)
			(end 0.508 -0.9398)
			(stroke
				(width 0)
				(type default)
			)
			(fill no)
			(layer "F.Fab")
		)
		(pad "1" smd custom
			(at 0 -0.4445 270)
			(size 0.1397 0.1397)
			(layers "F.Cu" "F.Mask" "F.Paste")
			(net "EXP_SDA_0")
			(options
				(clearance outline)
				(anchor circle)
			)
			(primitives
				(gr_poly
					(pts
						(arc
							(start -0.1778 -0.2794)
							(mid -0.249642 -0.249642)
							(end -0.2794 -0.1778)
						)
						(arc
							(start -0.2794 0.1778)
							(mid -0.249642 0.249642)
							(end -0.1778 0.2794)
						)
						(arc
							(start 0.1778 0.2794)
							(mid 0.249642 0.249642)
							(end 0.2794 0.1778)
						)
						(arc
							(start 0.2794 -0.1778)
							(mid 0.249642 -0.249642)
							(end 0.1778 -0.2794)
						)
					)
					(width 0)
					(fill yes)
				)
			)
		)
		(pad "2" smd custom
			(at 0 0.4445 270)
			(size 0.1397 0.1397)
			(layers "F.Cu" "F.Mask" "F.Paste")
			(net "P1V8_E")
			(options
				(clearance outline)
				(anchor circle)
			)
			(primitives
				(gr_poly
					(pts
						(arc
							(start -0.1778 -0.2794)
							(mid -0.249642 -0.249642)
							(end -0.2794 -0.1778)
						)
						(arc
							(start -0.2794 0.1778)
							(mid -0.249642 0.249642)
							(end -0.1778 0.2794)
						)
						(arc
							(start 0.1778 0.2794)
							(mid 0.249642 0.249642)
							(end 0.2794 0.1778)
						)
						(arc
							(start 0.2794 -0.1778)
							(mid 0.249642 -0.249642)
							(end 0.1778 -0.2794)
						)
					)
					(width 0)
					(fill yes)
				)
			)
		)
	)
	(footprint ""
		(layer "F.Cu")
		(at 108.85297 -114.3 180)
		(property "Reference" "SC1082"
			(at 0 0 180)
			(layer "F.SilkS")
			(hide yes)
			(effects
				(font
					(size 1.27 1.27)
				)
			)
		)
		(property "Value" "SCD01U10V1KX-GP"
			(at -2.8321 -1.7399 180)
			(unlocked yes)
			(layer "F.Fab")
			(hide yes)
			(effects
				(font
					(size 1.016 1.016)
					(thickness 0.1524)
				)
			)
		)
		(property "Device Type" "C0201H13"
			(at -2.8321 -3.2639 180)
			(unlocked yes)
			(layer "F.Fab")
			(hide yes)
			(effects
				(font
					(size 1.016 1.016)
					(thickness 0.1524)
				)
			)
		)
		(duplicate_pad_numbers_are_jumpers no)
		(fp_rect
			(start -0.2794 0.6477)
			(end 0.2794 -0.6477)
			(stroke
				(width 0)
				(type default)
			)
			(fill no)
			(layer "F.CrtYd")
		)
		(fp_rect
			(start -0.2794 0.6477)
			(end 0.2794 -0.6477)
			(stroke
				(width 0)
				(type default)
			)
			(fill no)
			(layer "F.Fab")
		)
		(pad "1" smd custom
			(at 0 -0.2794 180)
			(size 0.0762 0.0762)
			(layers "F.Cu" "F.Mask" "F.Paste")
			(net "SAS_HDD_TX7_N")
			(options
				(clearance outline)
				(anchor circle)
			)
			(primitives
				(gr_poly
					(pts
						(arc
							(start 0.1524 -0.127)
							(mid 0.137521 -0.162921)
							(end 0.1016 -0.1778)
						)
						(arc
							(start -0.1016 -0.1778)
							(mid -0.137521 -0.162921)
							(end -0.1524 -0.127)
						)
						(arc
							(start -0.1524 0.127)
							(mid -0.137521 0.162921)
							(end -0.1016 0.1778)
						)
						(arc
							(start 0.1016 0.1778)
							(mid 0.137521 0.162921)
							(end 0.1524 0.127)
						)
					)
					(width 0)
					(fill yes)
				)
			)
		)
		(pad "2" smd custom
			(at 0 0.2794 180)
			(size 0.0762 0.0762)
			(layers "F.Cu" "F.Mask" "F.Paste")
			(net "SAS_EXP_GF_TX_DN11")
			(options
				(clearance outline)
				(anchor circle)
			)
			(primitives
				(gr_poly
					(pts
						(arc
							(start 0.1524 -0.127)
							(mid 0.137521 -0.162921)
							(end 0.1016 -0.1778)
						)
						(arc
							(start -0.1016 -0.1778)
							(mid -0.137521 -0.162921)
							(end -0.1524 -0.127)
						)
						(arc
							(start -0.1524 0.127)
							(mid -0.137521 0.162921)
							(end -0.1016 0.1778)
						)
						(arc
							(start 0.1016 0.1778)
							(mid 0.137521 0.162921)
							(end 0.1524 0.127)
						)
					)
					(width 0)
					(fill yes)
				)
			)
		)
	)
	(footprint ""
		(layer "F.Cu")
		(at 50.546 -109.601 -90)
		(property "Reference" "SC1307"
			(at 0 0 270)
			(layer "F.SilkS")
			(hide yes)
			(effects
				(font
					(size 1.27 1.27)
				)
			)
		)
		(property "Value" "SCD1U16V2KX-3GP"
			(at 1.1811 -2.7051 270)
			(unlocked yes)
			(layer "F.Fab")
			(hide yes)
			(effects
				(font
					(size 1.016 1.016)
					(thickness 0.1524)
				)
			)
		)
		(property "Device Type" "C402H22"
			(at 1.1811 -4.2291 270)
			(unlocked yes)
			(layer "F.Fab")
			(hide yes)
			(effects
				(font
					(size 1.016 1.016)
					(thickness 0.1524)
				)
			)
		)
		(duplicate_pad_numbers_are_jumpers no)
		(fp_rect
			(start -0.4318 0.9525)
			(end 0.4318 -0.9525)
			(stroke
				(width 0)
				(type default)
			)
			(fill no)
			(layer "F.CrtYd")
		)
		(fp_rect
			(start -0.4318 0.9525)
			(end 0.4318 -0.9525)
			(stroke
				(width 0)
				(type default)
			)
			(fill no)
			(layer "F.Fab")
		)
		(pad "1" smd custom
			(at 0 -0.4445 270)
			(size 0.1524 0.1524)
			(layers "F.Cu" "F.Mask" "F.Paste")
			(net "P5V_STBY")
			(options
				(clearance outline)
				(anchor circle)
			)
			(primitives
				(gr_poly
					(pts
						(arc
							(start 0.3048 -0.2032)
							(mid 0.275042 -0.275042)
							(end 0.2032 -0.3048)
						)
						(arc
							(start -0.2032 -0.3048)
							(mid -0.275042 -0.275042)
							(end -0.3048 -0.2032)
						)
						(arc
							(start -0.3048 0.2032)
							(mid -0.275042 0.275042)
							(end -0.2032 0.3048)
						)
						(arc
							(start 0.2032 0.3048)
							(mid 0.275042 0.275042)
							(end 0.3048 0.2032)
						)
					)
					(width 0)
					(fill yes)
				)
			)
		)
		(pad "2" smd custom
			(at 0 0.4445 270)
			(size 0.1524 0.1524)
			(layers "F.Cu" "F.Mask" "F.Paste")
			(net "GND")
			(options
				(clearance outline)
				(anchor circle)
			)
			(primitives
				(gr_poly
					(pts
						(arc
							(start 0.3048 -0.2032)
							(mid 0.275042 -0.275042)
							(end 0.2032 -0.3048)
						)
						(arc
							(start -0.2032 -0.3048)
							(mid -0.275042 -0.275042)
							(end -0.3048 -0.2032)
						)
						(arc
							(start -0.3048 0.2032)
							(mid -0.275042 0.275042)
							(end -0.2032 0.3048)
						)
						(arc
							(start 0.2032 0.3048)
							(mid 0.275042 0.275042)
							(end 0.3048 0.2032)
						)
					)
					(width 0)
					(fill yes)
				)
			)
		)
	)
	(footprint ""
		(layer "F.Cu")
		(at 30.011116 -80.379062 -90)
		(property "Reference" "R678"
			(at 0 0 270)
			(layer "F.SilkS")
			(hide yes)
			(effects
				(font
					(size 1.27 1.27)
				)
			)
		)
		(property "Value" "1KR2F-3-GP"
			(at 0.064008 -3.993896 270)
			(unlocked yes)
			(layer "F.Fab")
			(hide yes)
			(effects
				(font
					(size 1.016 1.016)
					(thickness 0.1524)
				)
			)
		)
		(property "Device Type" "R402H16"
			(at 0.064008 -5.517896 270)
			(unlocked yes)
			(layer "F.Fab")
			(hide yes)
			(effects
				(font
					(size 1.016 1.016)
					(thickness 0.1524)
				)
			)
		)
		(duplicate_pad_numbers_are_jumpers no)
		(fp_line
			(start -0.508 -0.9398)
			(end -0.508 0.9398)
			(stroke
				(width 0.1524)
				(type default)
			)
			(layer "F.SilkS")
		)
		(fp_line
			(start 0.508 -0.9398)
			(end -0.508 -0.9398)
			(stroke
				(width 0.1524)
				(type default)
			)
			(layer "F.SilkS")
		)
		(fp_rect
			(start -0.508 0.9398)
			(end 0.508 -0.9398)
			(stroke
				(width 0)
				(type default)
			)
			(fill no)
			(layer "F.CrtYd")
		)
		(fp_rect
			(start -0.508 0.9398)
			(end 0.508 -0.9398)
			(stroke
				(width 0)
				(type default)
			)
			(fill no)
			(layer "F.Fab")
		)
		(pad "1" smd custom
			(at 0 -0.4445 270)
			(size 0.1397 0.1397)
			(layers "F.Cu" "F.Mask" "F.Paste")
			(net "INTA_LED_RED_B")
			(options
				(clearance outline)
				(anchor circle)
			)
			(primitives
				(gr_poly
					(pts
						(arc
							(start -0.1778 -0.2794)
							(mid -0.249642 -0.249642)
							(end -0.2794 -0.1778)
						)
						(arc
							(start -0.2794 0.1778)
							(mid -0.249642 0.249642)
							(end -0.1778 0.2794)
						)
						(arc
							(start 0.1778 0.2794)
							(mid 0.249642 0.249642)
							(end 0.2794 0.1778)
						)
						(arc
							(start 0.2794 -0.1778)
							(mid 0.249642 -0.249642)
							(end 0.1778 -0.2794)
						)
					)
					(width 0)
					(fill yes)
				)
			)
		)
		(pad "2" smd custom
			(at 0 0.4445 270)
			(size 0.1397 0.1397)
			(layers "F.Cu" "F.Mask" "F.Paste")
			(net "GND")
			(options
				(clearance outline)
				(anchor circle)
			)
			(primitives
				(gr_poly
					(pts
						(arc
							(start -0.1778 -0.2794)
							(mid -0.249642 -0.249642)
							(end -0.2794 -0.1778)
						)
						(arc
							(start -0.2794 0.1778)
							(mid -0.249642 0.249642)
							(end -0.1778 0.2794)
						)
						(arc
							(start 0.1778 0.2794)
							(mid 0.249642 0.249642)
							(end 0.2794 0.1778)
						)
						(arc
							(start 0.2794 -0.1778)
							(mid 0.249642 -0.249642)
							(end 0.1778 -0.2794)
						)
					)
					(width 0)
					(fill yes)
				)
			)
		)
	)
	(footprint ""
		(layer "F.Cu")
		(at 198.755 -93.853 -90)
		(property "Reference" "PC236"
			(at 0 0 270)
			(layer "F.SilkS")
			(hide yes)
			(effects
				(font
					(size 1.27 1.27)
				)
			)
		)
		(property "Value" "SC22U6D3V5MX-2GP"
			(at -0.0762 -6.1214 270)
			(unlocked yes)
			(layer "F.Fab")
			(hide yes)
			(effects
				(font
					(size 1.016 1.016)
					(thickness 0.1524)
				)
			)
		)
		(property "Device Type" "C805H58"
			(at -0.0762 -8.1534 270)
			(unlocked yes)
			(layer "F.Fab")
			(hide yes)
			(effects
				(font
					(size 1.016 1.016)
					(thickness 0.1524)
				)
			)
		)
		(duplicate_pad_numbers_are_jumpers no)
		(fp_line
			(start 0.635 0)
			(end -0.635 0)
			(stroke
				(width 0.508)
				(type default)
			)
			(layer "F.SilkS")
		)
		(fp_rect
			(start -0.9652 1.778)
			(end 0.9652 -1.778)
			(stroke
				(width 0)
				(type default)
			)
			(fill no)
			(layer "F.CrtYd")
		)
		(fp_poly
			(pts
				(xy -0.9652 -1.778) (xy 0.9652 -1.778) (xy 0.9652 1.778) (xy -0.9652 1.778)
			)
			(stroke
				(width 0)
				(type default)
			)
			(fill no)
			(layer "F.Fab")
		)
		(pad "1" smd rect
			(at 0 -0.9652 270)
			(size 1.397 1.143)
			(layers "F.Cu" "F.Mask" "F.Paste")
			(net "P1V5_E")
		)
		(pad "2" smd rect
			(at 0 0.9652 270)
			(size 1.397 1.143)
			(layers "F.Cu" "F.Mask" "F.Paste")
			(net "GND")
		)
	)
	(footprint ""
		(layer "F.Cu")
		(at 18.238216 -202.11288)
		(property "Reference" "SC867"
			(at 0 0 0)
			(layer "F.SilkS")
			(hide yes)
			(effects
				(font
					(size 1.27 1.27)
				)
			)
		)
		(property "Value" "SCD1U16V2KX-3GP"
			(at 1.1811 -2.7051 0)
			(unlocked yes)
			(layer "F.Fab")
			(hide yes)
			(effects
				(font
					(size 1.016 1.016)
					(thickness 0.1524)
				)
			)
		)
		(property "Device Type" "C402H22"
			(at 1.1811 -4.2291 0)
			(unlocked yes)
			(layer "F.Fab")
			(hide yes)
			(effects
				(font
					(size 1.016 1.016)
					(thickness 0.1524)
				)
			)
		)
		(duplicate_pad_numbers_are_jumpers no)
		(fp_rect
			(start -0.4318 0.9525)
			(end 0.4318 -0.9525)
			(stroke
				(width 0)
				(type default)
			)
			(fill no)
			(layer "F.CrtYd")
		)
		(fp_rect
			(start -0.4318 0.9525)
			(end 0.4318 -0.9525)
			(stroke
				(width 0)
				(type default)
			)
			(fill no)
			(layer "F.Fab")
		)
		(pad "1" smd custom
			(at 0 -0.4445)
			(size 0.1524 0.1524)
			(layers "F.Cu" "F.Mask" "F.Paste")
			(net "BMC_I2C10_EN")
			(options
				(clearance outline)
				(anchor circle)
			)
			(primitives
				(gr_poly
					(pts
						(arc
							(start 0.3048 -0.2032)
							(mid 0.275042 -0.275042)
							(end 0.2032 -0.3048)
						)
						(arc
							(start -0.2032 -0.3048)
							(mid -0.275042 -0.275042)
							(end -0.3048 -0.2032)
						)
						(arc
							(start -0.3048 0.2032)
							(mid -0.275042 0.275042)
							(end -0.2032 0.3048)
						)
						(arc
							(start 0.2032 0.3048)
							(mid 0.275042 0.275042)
							(end 0.3048 0.2032)
						)
					)
					(width 0)
					(fill yes)
				)
			)
		)
		(pad "2" smd custom
			(at 0 0.4445)
			(size 0.1524 0.1524)
			(layers "F.Cu" "F.Mask" "F.Paste")
			(net "GND")
			(options
				(clearance outline)
				(anchor circle)
			)
			(primitives
				(gr_poly
					(pts
						(arc
							(start 0.3048 -0.2032)
							(mid 0.275042 -0.275042)
							(end 0.2032 -0.3048)
						)
						(arc
							(start -0.2032 -0.3048)
							(mid -0.275042 -0.275042)
							(end -0.3048 -0.2032)
						)
						(arc
							(start -0.3048 0.2032)
							(mid -0.275042 0.275042)
							(end -0.2032 0.3048)
						)
						(arc
							(start 0.2032 0.3048)
							(mid 0.275042 0.275042)
							(end 0.3048 0.2032)
						)
					)
					(width 0)
					(fill yes)
				)
			)
		)
	)
	(footprint ""
		(layer "F.Cu")
		(at 142.621 -64.135 90)
		(property "Reference" "SC1099"
			(at 0 0 90)
			(layer "F.SilkS")
			(hide yes)
			(effects
				(font
					(size 1.27 1.27)
				)
			)
		)
		(property "Value" "SCD1U16V2KX-3GP"
			(at 1.1811 -2.7051 90)
			(unlocked yes)
			(layer "F.Fab")
			(hide yes)
			(effects
				(font
					(size 1.016 1.016)
					(thickness 0.1524)
				)
			)
		)
		(property "Device Type" "C402H22"
			(at 1.1811 -4.2291 90)
			(unlocked yes)
			(layer "F.Fab")
			(hide yes)
			(effects
				(font
					(size 1.016 1.016)
					(thickness 0.1524)
				)
			)
		)
		(duplicate_pad_numbers_are_jumpers no)
		(fp_rect
			(start -0.4318 0.9525)
			(end 0.4318 -0.9525)
			(stroke
				(width 0)
				(type default)
			)
			(fill no)
			(layer "F.CrtYd")
		)
		(fp_rect
			(start -0.4318 0.9525)
			(end 0.4318 -0.9525)
			(stroke
				(width 0)
				(type default)
			)
			(fill no)
			(layer "F.Fab")
		)
		(pad "1" smd custom
			(at 0 -0.4445 90)
			(size 0.1524 0.1524)
			(layers "F.Cu" "F.Mask" "F.Paste")
			(net "P3V3")
			(options
				(clearance outline)
				(anchor circle)
			)
			(primitives
				(gr_poly
					(pts
						(arc
							(start 0.3048 -0.2032)
							(mid 0.275042 -0.275042)
							(end 0.2032 -0.3048)
						)
						(arc
							(start -0.2032 -0.3048)
							(mid -0.275042 -0.275042)
							(end -0.3048 -0.2032)
						)
						(arc
							(start -0.3048 0.2032)
							(mid -0.275042 0.275042)
							(end -0.2032 0.3048)
						)
						(arc
							(start 0.2032 0.3048)
							(mid 0.275042 0.275042)
							(end 0.3048 0.2032)
						)
					)
					(width 0)
					(fill yes)
				)
			)
		)
		(pad "2" smd custom
			(at 0 0.4445 90)
			(size 0.1524 0.1524)
			(layers "F.Cu" "F.Mask" "F.Paste")
			(net "GND")
			(options
				(clearance outline)
				(anchor circle)
			)
			(primitives
				(gr_poly
					(pts
						(arc
							(start 0.3048 -0.2032)
							(mid 0.275042 -0.275042)
							(end 0.2032 -0.3048)
						)
						(arc
							(start -0.2032 -0.3048)
							(mid -0.275042 -0.275042)
							(end -0.3048 -0.2032)
						)
						(arc
							(start -0.3048 0.2032)
							(mid -0.275042 0.275042)
							(end -0.2032 0.3048)
						)
						(arc
							(start 0.2032 0.3048)
							(mid 0.275042 0.275042)
							(end 0.3048 0.2032)
						)
					)
					(width 0)
					(fill yes)
				)
			)
		)
	)
	(footprint ""
		(layer "F.Cu")
		(at 90.786966 -60.325)
		(property "Reference" "STP39"
			(at 0 0 0)
			(layer "F.SilkS")
			(hide yes)
			(effects
				(font
					(size 1.27 1.27)
				)
			)
		)
		(property "Value" "TPAD28"
			(at 0.0127 -1.8034 0)
			(unlocked yes)
			(layer "F.Fab")
			(hide yes)
			(effects
				(font
					(size 1.016 1.016)
					(thickness 0.1524)
				)
			)
		)
		(property "Device Type" "TPAD28"
			(at 0.0127 -3.3274 0)
			(unlocked yes)
			(layer "F.Fab")
			(hide yes)
			(effects
				(font
					(size 1.016 1.016)
					(thickness 0.1524)
				)
			)
		)
		(duplicate_pad_numbers_are_jumpers no)
		(fp_poly
			(pts
				(arc
					(start 0.3556 0)
					(mid -0.3556 0)
					(end 0.3556 0)
				)
			)
			(stroke
				(width 0)
				(type default)
			)
			(fill no)
			(layer "F.CrtYd")
		)
		(fp_poly
			(pts
				(arc
					(start 0.6096 0)
					(mid -0.6096 0)
					(end 0.6096 0)
				)
			)
			(stroke
				(width 0)
				(type default)
			)
			(fill no)
			(layer "F.Fab")
		)
		(pad "1" smd circle
			(at 0 0)
			(size 0.7112 0.7112)
			(layers "F.Cu" "F.Mask" "F.Paste")
			(net "ICE1_TRST#")
		)
	)
	(footprint ""
		(layer "F.Cu")
		(at 47.4472 -119.0752)
		(property "Reference" "SC1300"
			(at 0 0 0)
			(layer "F.SilkS")
			(hide yes)
			(effects
				(font
					(size 1.27 1.27)
				)
			)
		)
		(property "Value" "SCD1U16V2KX-3GP"
			(at 1.1811 -2.7051 0)
			(unlocked yes)
			(layer "F.Fab")
			(hide yes)
			(effects
				(font
					(size 1.016 1.016)
					(thickness 0.1524)
				)
			)
		)
		(property "Device Type" "C402H22"
			(at 1.1811 -4.2291 0)
			(unlocked yes)
			(layer "F.Fab")
			(hide yes)
			(effects
				(font
					(size 1.016 1.016)
					(thickness 0.1524)
				)
			)
		)
		(duplicate_pad_numbers_are_jumpers no)
		(fp_rect
			(start -0.4318 0.9525)
			(end 0.4318 -0.9525)
			(stroke
				(width 0)
				(type default)
			)
			(fill no)
			(layer "F.CrtYd")
		)
		(fp_rect
			(start -0.4318 0.9525)
			(end 0.4318 -0.9525)
			(stroke
				(width 0)
				(type default)
			)
			(fill no)
			(layer "F.Fab")
		)
		(pad "1" smd custom
			(at 0 -0.4445)
			(size 0.1524 0.1524)
			(layers "F.Cu" "F.Mask" "F.Paste")
			(net "P1V8_E")
			(options
				(clearance outline)
				(anchor circle)
			)
			(primitives
				(gr_poly
					(pts
						(arc
							(start 0.3048 -0.2032)
							(mid 0.275042 -0.275042)
							(end 0.2032 -0.3048)
						)
						(arc
							(start -0.2032 -0.3048)
							(mid -0.275042 -0.275042)
							(end -0.3048 -0.2032)
						)
						(arc
							(start -0.3048 0.2032)
							(mid -0.275042 0.275042)
							(end -0.2032 0.3048)
						)
						(arc
							(start 0.2032 0.3048)
							(mid 0.275042 0.275042)
							(end 0.3048 0.2032)
						)
					)
					(width 0)
					(fill yes)
				)
			)
		)
		(pad "2" smd custom
			(at 0 0.4445)
			(size 0.1524 0.1524)
			(layers "F.Cu" "F.Mask" "F.Paste")
			(net "GND")
			(options
				(clearance outline)
				(anchor circle)
			)
			(primitives
				(gr_poly
					(pts
						(arc
							(start 0.3048 -0.2032)
							(mid 0.275042 -0.275042)
							(end 0.2032 -0.3048)
						)
						(arc
							(start -0.2032 -0.3048)
							(mid -0.275042 -0.275042)
							(end -0.3048 -0.2032)
						)
						(arc
							(start -0.3048 0.2032)
							(mid -0.275042 0.275042)
							(end -0.2032 0.3048)
						)
						(arc
							(start 0.2032 0.3048)
							(mid 0.275042 0.275042)
							(end 0.3048 0.2032)
						)
					)
					(width 0)
					(fill yes)
				)
			)
		)
	)
)
